(kicad_pcb
	(version 20260206)
	(generator "pcbnew")
	(generator_version "10.0")
	(general
		(thickness 1.6)
		(legacy_teardrops no)
	)
	(paper "A4")
	(title_block
		(title "01162023_DA0F0TEBIF0_F0T_Expander_BD_F_brd_V02_OCP.brd")
		(comment 1 "Grand Teton / footprints 8857-8863 of 9728")
	)
	(layers
		(0 "F.Cu" signal "TOP")
		(4 "In1.Cu" signal "GND")
		(6 "In2.Cu" signal "VCC")
		(8 "In3.Cu" signal "VCC1")
		(10 "In4.Cu" signal "GND1")
		(12 "In5.Cu" signal "IN1")
		(14 "In6.Cu" signal "GND2")
		(16 "In7.Cu" signal "IN2")
		(18 "In8.Cu" signal "GND3")
		(20 "In9.Cu" signal "IN3")
		(22 "In10.Cu" signal "GND4")
		(24 "In11.Cu" signal "IN4")
		(26 "In12.Cu" signal "GND5")
		(28 "In13.Cu" signal "IN5")
		(30 "In14.Cu" signal "GND6")
		(32 "In15.Cu" signal "IN6")
		(34 "In16.Cu" signal "GND7")
		(2 "B.Cu" signal "BOTTOM")
		(9 "F.Adhes" user "F.Adhesive")
		(11 "B.Adhes" user "B.Adhesive")
		(13 "F.Paste" user "Package Geometry/Pastemask Top")
		(15 "B.Paste" user "Package Geometry/Pastemask Bottom")
		(5 "F.SilkS" user "Ref Des/Silkscreen Top")
		(7 "B.SilkS" user "Ref Des/Silkscreen Bottom")
		(1 "F.Mask" user "Board Geometry/Soldermask Top")
		(3 "B.Mask" user "Board Geometry/Soldermask Bottom")
		(17 "Dwgs.User" user "User.Drawings")
		(19 "Cmts.User" user "User.Comments")
		(21 "Eco1.User" user "User.Eco1")
		(23 "Eco2.User" user "User.Eco2")
		(25 "Edge.Cuts" user "Board Geometry/Outline")
		(27 "Margin" user)
		(31 "F.CrtYd" user "Package Geometry/Place Bound Top")
		(29 "B.CrtYd" user "Package Geometry/Place Bound Bottom")
		(35 "F.Fab" user "Ref Des/Assembly Top")
		(33 "B.Fab" user "Ref Des/Assembly Bottom")
	)
	(footprint ""
		(layer "B.Cu")
		(at 133.030214 -212.381846 180)
		(property "Reference" "R987"
			(at 0 0 0)
			(layer "B.SilkS")
			(hide yes)
			(effects
				(font
					(size 1.27 1.27)
				)
				(justify mirror)
			)
		)
		(property "Value" ""
			(at 0 0 0)
			(layer "B.Fab")
			(effects
				(font
					(size 1.27 1.27)
				)
				(justify mirror)
			)
		)
		(duplicate_pad_numbers_are_jumpers no)
		(fp_line
			(start 0.7874 0.4064)
			(end 0.7874 -0.4064)
			(stroke
				(width 0.1524)
				(type default)
			)
			(layer "B.SilkS")
		)
		(fp_line
			(start 0.7874 -0.4064)
			(end -0.7874 -0.4064)
			(stroke
				(width 0.1524)
				(type default)
			)
			(layer "B.SilkS")
		)
		(fp_line
			(start -0.7874 0.4064)
			(end 0.7874 0.4064)
			(stroke
				(width 0.1524)
				(type default)
			)
			(layer "B.SilkS")
		)
		(fp_line
			(start -0.7874 -0.4064)
			(end -0.7874 0.4064)
			(stroke
				(width 0.1524)
				(type default)
			)
			(layer "B.SilkS")
		)
		(fp_line
			(start 0.67945 0.3048)
			(end 0.67945 -0.305054)
			(stroke
				(width 0.1)
				(type default)
			)
			(layer "B.Fab")
		)
		(fp_line
			(start 0.67945 -0.305054)
			(end 0.12065 -0.305054)
			(stroke
				(width 0.1)
				(type default)
			)
			(layer "B.Fab")
		)
		(fp_line
			(start 0.12065 0.3048)
			(end 0.67945 0.3048)
			(stroke
				(width 0.1)
				(type default)
			)
			(layer "B.Fab")
		)
		(fp_line
			(start 0.12065 0.2794)
			(end 0.12065 0.3048)
			(stroke
				(width 0.1)
				(type default)
			)
			(layer "B.Fab")
		)
		(fp_line
			(start 0.12065 -0.2794)
			(end -0.12065 -0.2794)
			(stroke
				(width 0.1)
				(type default)
			)
			(layer "B.Fab")
		)
		(fp_line
			(start 0.12065 -0.305054)
			(end 0.12065 -0.2794)
			(stroke
				(width 0.1)
				(type default)
			)
			(layer "B.Fab")
		)
		(fp_line
			(start -0.120396 0.3048)
			(end -0.120396 0.2794)
			(stroke
				(width 0.1)
				(type default)
			)
			(layer "B.Fab")
		)
		(fp_line
			(start -0.120396 0.2794)
			(end 0.12065 0.2794)
			(stroke
				(width 0.1)
				(type default)
			)
			(layer "B.Fab")
		)
		(fp_line
			(start -0.12065 -0.2794)
			(end -0.12065 -0.3048)
			(stroke
				(width 0.1)
				(type default)
			)
			(layer "B.Fab")
		)
		(fp_line
			(start -0.12065 -0.3048)
			(end -0.67945 -0.3048)
			(stroke
				(width 0.1)
				(type default)
			)
			(layer "B.Fab")
		)
		(fp_line
			(start -0.67945 0.3048)
			(end -0.120396 0.3048)
			(stroke
				(width 0.1)
				(type default)
			)
			(layer "B.Fab")
		)
		(fp_line
			(start -0.67945 -0.3048)
			(end -0.67945 0.3048)
			(stroke
				(width 0.1)
				(type default)
			)
			(layer "B.Fab")
		)
		(pad "1" smd circle
			(at 0.40005 0)
			(size 0 0)
			(layers "B.Cu" "B.Mask" "B.Paste")
			(net "UART_PEX1_CLI_BUF_R_TX")
		)
		(pad "2" smd circle
			(at -0.40005 0)
			(size 0 0)
			(layers "B.Cu" "B.Mask" "B.Paste")
			(net "UART_PEX1_CLI_BUF_TX")
		)
	)
	(footprint ""
		(layer "B.Cu")
		(at 98.90125 -376.488706)
		(property "Reference" "R1832"
			(at 0 0 0)
			(layer "B.SilkS")
			(hide yes)
			(effects
				(font
					(size 1.27 1.27)
				)
				(justify mirror)
			)
		)
		(property "Value" ""
			(at 0 0 0)
			(layer "B.Fab")
			(effects
				(font
					(size 1.27 1.27)
				)
				(justify mirror)
			)
		)
		(duplicate_pad_numbers_are_jumpers no)
		(fp_line
			(start -0.7874 -0.4064)
			(end -0.7874 0.4064)
			(stroke
				(width 0.1524)
				(type default)
			)
			(layer "B.SilkS")
		)
		(fp_line
			(start -0.7874 0.4064)
			(end 0.7874 0.4064)
			(stroke
				(width 0.1524)
				(type default)
			)
			(layer "B.SilkS")
		)
		(fp_line
			(start 0.7874 -0.4064)
			(end -0.7874 -0.4064)
			(stroke
				(width 0.1524)
				(type default)
			)
			(layer "B.SilkS")
		)
		(fp_line
			(start 0.7874 0.4064)
			(end 0.7874 -0.4064)
			(stroke
				(width 0.1524)
				(type default)
			)
			(layer "B.SilkS")
		)
		(fp_line
			(start -0.67945 -0.3048)
			(end -0.67945 0.3048)
			(stroke
				(width 0.1)
				(type default)
			)
			(layer "B.Fab")
		)
		(fp_line
			(start -0.67945 0.3048)
			(end -0.120396 0.3048)
			(stroke
				(width 0.1)
				(type default)
			)
			(layer "B.Fab")
		)
		(fp_line
			(start -0.12065 -0.3048)
			(end -0.67945 -0.3048)
			(stroke
				(width 0.1)
				(type default)
			)
			(layer "B.Fab")
		)
		(fp_line
			(start -0.12065 -0.2794)
			(end -0.12065 -0.3048)
			(stroke
				(width 0.1)
				(type default)
			)
			(layer "B.Fab")
		)
		(fp_line
			(start -0.120396 0.2794)
			(end 0.12065 0.2794)
			(stroke
				(width 0.1)
				(type default)
			)
			(layer "B.Fab")
		)
		(fp_line
			(start -0.120396 0.3048)
			(end -0.120396 0.2794)
			(stroke
				(width 0.1)
				(type default)
			)
			(layer "B.Fab")
		)
		(fp_line
			(start 0.12065 -0.305054)
			(end 0.12065 -0.2794)
			(stroke
				(width 0.1)
				(type default)
			)
			(layer "B.Fab")
		)
		(fp_line
			(start 0.12065 -0.2794)
			(end -0.12065 -0.2794)
			(stroke
				(width 0.1)
				(type default)
			)
			(layer "B.Fab")
		)
		(fp_line
			(start 0.12065 0.2794)
			(end 0.12065 0.3048)
			(stroke
				(width 0.1)
				(type default)
			)
			(layer "B.Fab")
		)
		(fp_line
			(start 0.12065 0.3048)
			(end 0.67945 0.3048)
			(stroke
				(width 0.1)
				(type default)
			)
			(layer "B.Fab")
		)
		(fp_line
			(start 0.67945 -0.305054)
			(end 0.12065 -0.305054)
			(stroke
				(width 0.1)
				(type default)
			)
			(layer "B.Fab")
		)
		(fp_line
			(start 0.67945 0.3048)
			(end 0.67945 -0.305054)
			(stroke
				(width 0.1)
				(type default)
			)
			(layer "B.Fab")
		)
		(pad "1" smd circle
			(at 0.40005 0 180)
			(size 0 0)
			(layers "B.Cu" "B.Mask" "B.Paste")
			(net "SMB_GPU_2_R_SDA")
		)
		(pad "2" smd circle
			(at -0.40005 0 180)
			(size 0 0)
			(layers "B.Cu" "B.Mask" "B.Paste")
			(net "SMB_GPU_2_SDA")
		)
	)
	(footprint ""
		(layer "B.Cu")
		(at 415.07664 -293.99992 90)
		(property "Reference" "C1930"
			(at 0 0 90)
			(layer "B.SilkS")
			(hide yes)
			(effects
				(font
					(size 1.27 1.27)
				)
				(justify mirror)
			)
		)
		(property "Value" ""
			(at 0 0 90)
			(layer "B.Fab")
			(effects
				(font
					(size 1.27 1.27)
				)
				(justify mirror)
			)
		)
		(duplicate_pad_numbers_are_jumpers no)
		(fp_line
			(start 0.299974 -0.150114)
			(end -0.299974 -0.150114)
			(stroke
				(width 0.1)
				(type default)
			)
			(layer "B.Fab")
		)
		(fp_line
			(start -0.299974 -0.150114)
			(end -0.299974 0.150114)
			(stroke
				(width 0.1)
				(type default)
			)
			(layer "B.Fab")
		)
		(fp_line
			(start 0.299974 0.150114)
			(end 0.299974 -0.150114)
			(stroke
				(width 0.1)
				(type default)
			)
			(layer "B.Fab")
		)
		(fp_line
			(start -0.299974 0.150114)
			(end 0.299974 0.150114)
			(stroke
				(width 0.1)
				(type default)
			)
			(layer "B.Fab")
		)
		(pad "1" smd rect
			(at 0.2667 0 270)
			(size 0.3048 0.381)
			(layers "B.Cu" "B.Mask" "B.Paste")
			(net "P0V8_SERDES_VDDA_PEX3")
		)
		(pad "2" smd rect
			(at -0.2667 0 270)
			(size 0.3048 0.381)
			(layers "B.Cu" "B.Mask" "B.Paste")
			(net "GND")
		)
	)
	(footprint ""
		(layer "B.Cu")
		(at 338.582 -207.772 90)
		(property "Reference" "R4135"
			(at 0 0 90)
			(layer "B.SilkS")
			(hide yes)
			(effects
				(font
					(size 1.27 1.27)
				)
				(justify mirror)
			)
		)
		(property "Value" ""
			(at 0 0 90)
			(layer "B.Fab")
			(effects
				(font
					(size 1.27 1.27)
				)
				(justify mirror)
			)
		)
		(duplicate_pad_numbers_are_jumpers no)
		(fp_line
			(start 0.7874 -0.4064)
			(end -0.7874 -0.4064)
			(stroke
				(width 0.1524)
				(type default)
			)
			(layer "B.SilkS")
		)
		(fp_line
			(start -0.7874 -0.4064)
			(end -0.7874 0.4064)
			(stroke
				(width 0.1524)
				(type default)
			)
			(layer "B.SilkS")
		)
		(fp_line
			(start 0.7874 0.4064)
			(end 0.7874 -0.4064)
			(stroke
				(width 0.1524)
				(type default)
			)
			(layer "B.SilkS")
		)
		(fp_line
			(start -0.7874 0.4064)
			(end 0.7874 0.4064)
			(stroke
				(width 0.1524)
				(type default)
			)
			(layer "B.SilkS")
		)
		(fp_line
			(start 0.67945 -0.305054)
			(end 0.12065 -0.305054)
			(stroke
				(width 0.1)
				(type default)
			)
			(layer "B.Fab")
		)
		(fp_line
			(start 0.12065 -0.305054)
			(end 0.12065 -0.2794)
			(stroke
				(width 0.1)
				(type default)
			)
			(layer "B.Fab")
		)
		(fp_line
			(start -0.12065 -0.3048)
			(end -0.67945 -0.3048)
			(stroke
				(width 0.1)
				(type default)
			)
			(layer "B.Fab")
		)
		(fp_line
			(start -0.67945 -0.3048)
			(end -0.67945 0.3048)
			(stroke
				(width 0.1)
				(type default)
			)
			(layer "B.Fab")
		)
		(fp_line
			(start 0.12065 -0.2794)
			(end -0.12065 -0.2794)
			(stroke
				(width 0.1)
				(type default)
			)
			(layer "B.Fab")
		)
		(fp_line
			(start -0.12065 -0.2794)
			(end -0.12065 -0.3048)
			(stroke
				(width 0.1)
				(type default)
			)
			(layer "B.Fab")
		)
		(fp_line
			(start 0.12065 0.2794)
			(end 0.12065 0.3048)
			(stroke
				(width 0.1)
				(type default)
			)
			(layer "B.Fab")
		)
		(fp_line
			(start -0.120396 0.2794)
			(end 0.12065 0.2794)
			(stroke
				(width 0.1)
				(type default)
			)
			(layer "B.Fab")
		)
		(fp_line
			(start 0.67945 0.3048)
			(end 0.67945 -0.305054)
			(stroke
				(width 0.1)
				(type default)
			)
			(layer "B.Fab")
		)
		(fp_line
			(start 0.12065 0.3048)
			(end 0.67945 0.3048)
			(stroke
				(width 0.1)
				(type default)
			)
			(layer "B.Fab")
		)
		(fp_line
			(start -0.120396 0.3048)
			(end -0.120396 0.2794)
			(stroke
				(width 0.1)
				(type default)
			)
			(layer "B.Fab")
		)
		(fp_line
			(start -0.67945 0.3048)
			(end -0.120396 0.3048)
			(stroke
				(width 0.1)
				(type default)
			)
			(layer "B.Fab")
		)
		(pad "1" smd circle
			(at 0.40005 0 270)
			(size 0 0)
			(layers "B.Cu" "B.Mask" "B.Paste")
			(net "SSD13_PWR_EN")
		)
		(pad "2" smd circle
			(at -0.40005 0 270)
			(size 0 0)
			(layers "B.Cu" "B.Mask" "B.Paste")
			(net "SSD13_PWR_EN_R")
		)
	)
	(footprint ""
		(layer "B.Cu")
		(at 206.164942 -259.311648 90)
		(property "Reference" "R6344"
			(at 0 0 90)
			(layer "B.SilkS")
			(hide yes)
			(effects
				(font
					(size 1.27 1.27)
				)
				(justify mirror)
			)
		)
		(property "Value" ""
			(at 0 0 90)
			(layer "B.Fab")
			(effects
				(font
					(size 1.27 1.27)
				)
				(justify mirror)
			)
		)
		(duplicate_pad_numbers_are_jumpers no)
		(fp_line
			(start 0.7874 -0.4064)
			(end -0.7874 -0.4064)
			(stroke
				(width 0.1524)
				(type default)
			)
			(layer "B.SilkS")
		)
		(fp_line
			(start -0.7874 -0.4064)
			(end -0.7874 0.4064)
			(stroke
				(width 0.1524)
				(type default)
			)
			(layer "B.SilkS")
		)
		(fp_line
			(start 0.7874 0.4064)
			(end 0.7874 -0.4064)
			(stroke
				(width 0.1524)
				(type default)
			)
			(layer "B.SilkS")
		)
		(fp_line
			(start -0.7874 0.4064)
			(end 0.7874 0.4064)
			(stroke
				(width 0.1524)
				(type default)
			)
			(layer "B.SilkS")
		)
		(fp_line
			(start 0.67945 -0.305054)
			(end 0.12065 -0.305054)
			(stroke
				(width 0.1)
				(type default)
			)
			(layer "B.Fab")
		)
		(fp_line
			(start 0.12065 -0.305054)
			(end 0.12065 -0.2794)
			(stroke
				(width 0.1)
				(type default)
			)
			(layer "B.Fab")
		)
		(fp_line
			(start -0.12065 -0.3048)
			(end -0.67945 -0.3048)
			(stroke
				(width 0.1)
				(type default)
			)
			(layer "B.Fab")
		)
		(fp_line
			(start -0.67945 -0.3048)
			(end -0.67945 0.3048)
			(stroke
				(width 0.1)
				(type default)
			)
			(layer "B.Fab")
		)
		(fp_line
			(start 0.12065 -0.2794)
			(end -0.12065 -0.2794)
			(stroke
				(width 0.1)
				(type default)
			)
			(layer "B.Fab")
		)
		(fp_line
			(start -0.12065 -0.2794)
			(end -0.12065 -0.3048)
			(stroke
				(width 0.1)
				(type default)
			)
			(layer "B.Fab")
		)
		(fp_line
			(start 0.12065 0.2794)
			(end 0.12065 0.3048)
			(stroke
				(width 0.1)
				(type default)
			)
			(layer "B.Fab")
		)
		(fp_line
			(start -0.120396 0.2794)
			(end 0.12065 0.2794)
			(stroke
				(width 0.1)
				(type default)
			)
			(layer "B.Fab")
		)
		(fp_line
			(start 0.67945 0.3048)
			(end 0.67945 -0.305054)
			(stroke
				(width 0.1)
				(type default)
			)
			(layer "B.Fab")
		)
		(fp_line
			(start 0.12065 0.3048)
			(end 0.67945 0.3048)
			(stroke
				(width 0.1)
				(type default)
			)
			(layer "B.Fab")
		)
		(fp_line
			(start -0.120396 0.3048)
			(end -0.120396 0.2794)
			(stroke
				(width 0.1)
				(type default)
			)
			(layer "B.Fab")
		)
		(fp_line
			(start -0.67945 0.3048)
			(end -0.120396 0.3048)
			(stroke
				(width 0.1)
				(type default)
			)
			(layer "B.Fab")
		)
		(pad "1" smd circle
			(at 0.40005 0 270)
			(size 0 0)
			(layers "B.Cu" "B.Mask" "B.Paste")
			(net "P1V8_PEX")
		)
		(pad "2" smd circle
			(at -0.40005 0 270)
			(size 0 0)
			(layers "B.Cu" "B.Mask" "B.Paste")
			(net "SMB_PEX1_MUX_SDA")
		)
	)
	(footprint ""
		(layer "B.Cu")
		(at 411.683454 -108.462318 180)
		(property "Reference" "R387"
			(at 0 0 0)
			(layer "B.SilkS")
			(hide yes)
			(effects
				(font
					(size 1.27 1.27)
				)
				(justify mirror)
			)
		)
		(property "Value" ""
			(at 0 0 0)
			(layer "B.Fab")
			(effects
				(font
					(size 1.27 1.27)
				)
				(justify mirror)
			)
		)
		(duplicate_pad_numbers_are_jumpers no)
		(fp_line
			(start 0.7874 0.4064)
			(end 0.7874 -0.4064)
			(stroke
				(width 0.1524)
				(type default)
			)
			(layer "B.SilkS")
		)
		(fp_line
			(start 0.7874 -0.4064)
			(end -0.7874 -0.4064)
			(stroke
				(width 0.1524)
				(type default)
			)
			(layer "B.SilkS")
		)
		(fp_line
			(start -0.7874 0.4064)
			(end 0.7874 0.4064)
			(stroke
				(width 0.1524)
				(type default)
			)
			(layer "B.SilkS")
		)
		(fp_line
			(start -0.7874 -0.4064)
			(end -0.7874 0.4064)
			(stroke
				(width 0.1524)
				(type default)
			)
			(layer "B.SilkS")
		)
		(fp_line
			(start 0.67945 0.3048)
			(end 0.67945 -0.305054)
			(stroke
				(width 0.1)
				(type default)
			)
			(layer "B.Fab")
		)
		(fp_line
			(start 0.67945 -0.305054)
			(end 0.12065 -0.305054)
			(stroke
				(width 0.1)
				(type default)
			)
			(layer "B.Fab")
		)
		(fp_line
			(start 0.12065 0.3048)
			(end 0.67945 0.3048)
			(stroke
				(width 0.1)
				(type default)
			)
			(layer "B.Fab")
		)
		(fp_line
			(start 0.12065 0.2794)
			(end 0.12065 0.3048)
			(stroke
				(width 0.1)
				(type default)
			)
			(layer "B.Fab")
		)
		(fp_line
			(start 0.12065 -0.2794)
			(end -0.12065 -0.2794)
			(stroke
				(width 0.1)
				(type default)
			)
			(layer "B.Fab")
		)
		(fp_line
			(start 0.12065 -0.305054)
			(end 0.12065 -0.2794)
			(stroke
				(width 0.1)
				(type default)
			)
			(layer "B.Fab")
		)
		(fp_line
			(start -0.120396 0.3048)
			(end -0.120396 0.2794)
			(stroke
				(width 0.1)
				(type default)
			)
			(layer "B.Fab")
		)
		(fp_line
			(start -0.120396 0.2794)
			(end 0.12065 0.2794)
			(stroke
				(width 0.1)
				(type default)
			)
			(layer "B.Fab")
		)
		(fp_line
			(start -0.12065 -0.2794)
			(end -0.12065 -0.3048)
			(stroke
				(width 0.1)
				(type default)
			)
			(layer "B.Fab")
		)
		(fp_line
			(start -0.12065 -0.3048)
			(end -0.67945 -0.3048)
			(stroke
				(width 0.1)
				(type default)
			)
			(layer "B.Fab")
		)
		(fp_line
			(start -0.67945 0.3048)
			(end -0.120396 0.3048)
			(stroke
				(width 0.1)
				(type default)
			)
			(layer "B.Fab")
		)
		(fp_line
			(start -0.67945 -0.3048)
			(end -0.67945 0.3048)
			(stroke
				(width 0.1)
				(type default)
			)
			(layer "B.Fab")
		)
		(pad "1" smd circle
			(at 0.40005 0)
			(size 0 0)
			(layers "B.Cu" "B.Mask" "B.Paste")
			(net "NIC7_BIF0_N")
		)
		(pad "2" smd circle
			(at -0.40005 0)
			(size 0 0)
			(layers "B.Cu" "B.Mask" "B.Paste")
			(net "GND")
		)
	)
	(footprint ""
		(layer "B.Cu")
		(at 344.043 -233.553 90)
		(property "Reference" "R3566"
			(at 0 0 90)
			(layer "B.SilkS")
			(hide yes)
			(effects
				(font
					(size 1.27 1.27)
				)
				(justify mirror)
			)
		)
		(property "Value" ""
			(at 0 0 90)
			(layer "B.Fab")
			(effects
				(font
					(size 1.27 1.27)
				)
				(justify mirror)
			)
		)
		(duplicate_pad_numbers_are_jumpers no)
		(fp_line
			(start 0.7874 -0.4064)
			(end -0.7874 -0.4064)
			(stroke
				(width 0.1524)
				(type default)
			)
			(layer "B.SilkS")
		)
		(fp_line
			(start -0.7874 -0.4064)
			(end -0.7874 0.4064)
			(stroke
				(width 0.1524)
				(type default)
			)
			(layer "B.SilkS")
		)
		(fp_line
			(start 0.7874 0.4064)
			(end 0.7874 -0.4064)
			(stroke
				(width 0.1524)
				(type default)
			)
			(layer "B.SilkS")
		)
		(fp_line
			(start -0.7874 0.4064)
			(end 0.7874 0.4064)
			(stroke
				(width 0.1524)
				(type default)
			)
			(layer "B.SilkS")
		)
		(fp_line
			(start 0.67945 -0.305054)
			(end 0.12065 -0.305054)
			(stroke
				(width 0.1)
				(type default)
			)
			(layer "B.Fab")
		)
		(fp_line
			(start 0.12065 -0.305054)
			(end 0.12065 -0.2794)
			(stroke
				(width 0.1)
				(type default)
			)
			(layer "B.Fab")
		)
		(fp_line
			(start -0.12065 -0.3048)
			(end -0.67945 -0.3048)
			(stroke
				(width 0.1)
				(type default)
			)
			(layer "B.Fab")
		)
		(fp_line
			(start -0.67945 -0.3048)
			(end -0.67945 0.3048)
			(stroke
				(width 0.1)
				(type default)
			)
			(layer "B.Fab")
		)
		(fp_line
			(start 0.12065 -0.2794)
			(end -0.12065 -0.2794)
			(stroke
				(width 0.1)
				(type default)
			)
			(layer "B.Fab")
		)
		(fp_line
			(start -0.12065 -0.2794)
			(end -0.12065 -0.3048)
			(stroke
				(width 0.1)
				(type default)
			)
			(layer "B.Fab")
		)
		(fp_line
			(start 0.12065 0.2794)
			(end 0.12065 0.3048)
			(stroke
				(width 0.1)
				(type default)
			)
			(layer "B.Fab")
		)
		(fp_line
			(start -0.120396 0.2794)
			(end 0.12065 0.2794)
			(stroke
				(width 0.1)
				(type default)
			)
			(layer "B.Fab")
		)
		(fp_line
			(start 0.67945 0.3048)
			(end 0.67945 -0.305054)
			(stroke
				(width 0.1)
				(type default)
			)
			(layer "B.Fab")
		)
		(fp_line
			(start 0.12065 0.3048)
			(end 0.67945 0.3048)
			(stroke
				(width 0.1)
				(type default)
			)
			(layer "B.Fab")
		)
		(fp_line
			(start -0.120396 0.3048)
			(end -0.120396 0.2794)
			(stroke
				(width 0.1)
				(type default)
			)
			(layer "B.Fab")
		)
		(fp_line
			(start -0.67945 0.3048)
			(end -0.120396 0.3048)
			(stroke
				(width 0.1)
				(type default)
			)
			(layer "B.Fab")
		)
		(pad "1" smd circle
			(at 0.40005 0 270)
			(size 0 0)
			(layers "B.Cu" "B.Mask" "B.Paste")
			(net "SSD5_PWRDIS_R")
		)
		(pad "2" smd circle
			(at -0.40005 0 270)
			(size 0 0)
			(layers "B.Cu" "B.Mask" "B.Paste")
			(net "SSD5_PWRDIS")
		)
	)
)
